# BASEBOARD_FAB2 (Tioga Pass) — schematic netlist excerpt (pin names and nets, part order shuffled) for the footprints in the layout excerpt that follows; sources: Cadence DE-HDL packaged netlist, KiCad conversion of Wiwynn_Tioga_Pass_MB.brd

R3P62  RES  4.75K 1% EMPTY  pkg 0402  page 126 : A = P3V3_STBY ; B = FM_FLASH_ATTACH_CFG_STRAP
C9B2  CAP  10UF 16V 10% X6S  pkg 0805  page 172 : A = P12V_HDD_SATA ; B = GND
C4C1  CAPP  470UF 2.5V 20% ALUM  pkg 3018  page 193 : A = PVCCIOMCP_CPU1 ; B = GND

(kicad_pcb
	(version 20260206)
	(generator "pcbnew")
	(generator_version "10.0")
	(general
		(thickness 1.6)
		(legacy_teardrops no)
	)
	(paper "A4")
	(title_block
		(title "Wiwynn_Tioga_Pass_MB.brd")
		(comment 1 "Tioga Pass / footprints 1707-1709 of 4770")
	)
	(layers
		(0 "F.Cu" signal "TOP")
		(4 "In1.Cu" signal "L2GND")
		(6 "In2.Cu" signal "L3")
		(8 "In3.Cu" signal "L4GND")
		(10 "In4.Cu" signal "L5")
		(12 "In5.Cu" signal "L6GND")
		(14 "In6.Cu" signal "L7VCC")
		(16 "In7.Cu" signal "L8VCC")
		(18 "In8.Cu" signal "L9GND")
		(20 "In9.Cu" signal "L10")
		(22 "In10.Cu" signal "L11GND")
		(24 "In11.Cu" signal "L12")
		(26 "In12.Cu" signal "L13GND")
		(2 "B.Cu" signal "BOTTOM")
		(9 "F.Adhes" user "F.Adhesive")
		(11 "B.Adhes" user "B.Adhesive")
		(13 "F.Paste" user "Package Geometry/Pastemask Top")
		(15 "B.Paste" user "Package Geometry/Pastemask Bottom")
		(5 "F.SilkS" user "Ref Des/Silkscreen Top")
		(7 "B.SilkS" user "Ref Des/Silkscreen Bottom")
		(1 "F.Mask" user "Board Geometry/Soldermask Top")
		(3 "B.Mask" user "Board Geometry/Soldermask Bottom")
		(17 "Dwgs.User" user "User.Drawings")
		(19 "Cmts.User" user "User.Comments")
		(21 "Eco1.User" user "User.Eco1")
		(23 "Eco2.User" user "User.Eco2")
		(25 "Edge.Cuts" user "Board Geometry/Outline")
		(27 "Margin" user)
		(31 "F.CrtYd" user "Package Geometry/Place Bound Top")
		(29 "B.CrtYd" user "Package Geometry/Place Bound Bottom")
		(35 "F.Fab" user "Ref Des/Assembly Top")
		(33 "B.Fab" user "Ref Des/Assembly Bottom")
	)
	(footprint ""
		(layer "F.Cu")
		(at 451.739 -131.2418 -90)
		(property "Reference" "C9B2"
			(at 0 0 270)
			(layer "F.SilkS")
			(hide yes)
			(effects
				(font
					(size 1.27 1.27)
				)
			)
		)
		(property "Value" ""
			(at 0 0 270)
			(layer "F.Fab")
			(effects
				(font
					(size 1.27 1.27)
				)
			)
		)
		(duplicate_pad_numbers_are_jumpers no)
		(fp_poly
			(pts
				(xy -0.7239 -0.2159) (xy 0.7239 -0.2159) (xy 0.7239 1.9939) (xy -0.7239 1.9939)
			)
			(stroke
				(width 0)
				(type default)
			)
			(fill no)
			(layer "F.CrtYd")
		)
		(fp_line
			(start -0.7239 1.9939)
			(end 0.7239 1.9939)
			(stroke
				(width 0.1)
				(type default)
			)
			(layer "F.Fab")
		)
		(fp_line
			(start 0.7239 1.9939)
			(end 0.7239 -0.2159)
			(stroke
				(width 0.1)
				(type default)
			)
			(layer "F.Fab")
		)
		(fp_line
			(start -0.7239 -0.2159)
			(end -0.7239 1.9939)
			(stroke
				(width 0.1)
				(type default)
			)
			(layer "F.Fab")
		)
		(fp_line
			(start 0.7239 -0.2159)
			(end -0.7239 -0.2159)
			(stroke
				(width 0.1)
				(type default)
			)
			(layer "F.Fab")
		)
		(pad "1" smd rect
			(at 0 0 270)
			(size 1.27 1.016)
			(layers "F.Cu" "F.Mask" "F.Paste")
			(net "P12V_HDD_SATA")
		)
		(pad "2" smd rect
			(at 0 1.778 270)
			(size 1.27 1.016)
			(layers "F.Cu" "F.Mask" "F.Paste")
			(net "GND")
		)
		(zone
			(layer "F.Cu")
			(hatch none 0.5)
			(connect_pads
				(clearance 0)
			)
			(min_thickness 0.25)
			(keepout
				(tracks not_allowed)
				(vias allowed)
				(pads allowed)
				(copperpour not_allowed)
				(footprints allowed)
			)
			(placement
				(enabled no)
				(sheetname "")
			)
			(fill
				(thermal_gap 0.5)
				(thermal_bridge_width 0.5)
				(island_removal_mode 0)
			)
			(polygon
				(pts
					(xy 451.231 -131.8768) (xy 451.231 -130.6068) (xy 450.469 -130.6068) (xy 450.469 -131.8768)
				)
			)
		)
	)
	(footprint ""
		(layer "F.Cu")
		(at 169.247058 -105.4354)
		(property "Reference" "C4C1"
			(at -3.104388 3.8354 90)
			(unlocked yes)
			(layer "F.SilkS")
			(effects
				(font
					(size 0.7874 0.5842)
					(thickness 0.1524)
				)
			)
		)
		(property "Value" ""
			(at 0 0 0)
			(layer "F.Fab")
			(effects
				(font
					(size 1.27 1.27)
				)
			)
		)
		(duplicate_pad_numbers_are_jumpers no)
		(fp_line
			(start -2.563114 -1.616456)
			(end -2.563114 1.633728)
			(stroke
				(width 0.1524)
				(type default)
			)
			(layer "F.SilkS")
		)
		(fp_line
			(start -2.563114 1.633728)
			(end -1.6002 1.633728)
			(stroke
				(width 0.1524)
				(type default)
			)
			(layer "F.SilkS")
		)
		(fp_line
			(start -2.286 7.366)
			(end -2.286 1.632712)
			(stroke
				(width 0.1524)
				(type default)
			)
			(layer "F.SilkS")
		)
		(fp_line
			(start -2.286 7.366)
			(end -1.60147 7.366)
			(stroke
				(width 0.1524)
				(type default)
			)
			(layer "F.SilkS")
		)
		(fp_line
			(start -1.6002 -1.616456)
			(end -2.563114 -1.616456)
			(stroke
				(width 0.1524)
				(type default)
			)
			(layer "F.SilkS")
		)
		(fp_line
			(start 1.6002 -1.616456)
			(end 2.504948 -1.616456)
			(stroke
				(width 0.1524)
				(type default)
			)
			(layer "F.SilkS")
		)
		(fp_line
			(start 2.286 7.366)
			(end 1.600708 7.366)
			(stroke
				(width 0.1524)
				(type default)
			)
			(layer "F.SilkS")
		)
		(fp_line
			(start 2.286 7.366)
			(end 2.286 1.63195)
			(stroke
				(width 0.1524)
				(type default)
			)
			(layer "F.SilkS")
		)
		(fp_line
			(start 2.504948 -1.616456)
			(end 2.504948 1.633728)
			(stroke
				(width 0.1524)
				(type default)
			)
			(layer "F.SilkS")
		)
		(fp_line
			(start 2.504948 1.633728)
			(end 1.6002 1.633728)
			(stroke
				(width 0.1524)
				(type default)
			)
			(layer "F.SilkS")
		)
		(fp_rect
			(start -2.286 7.366)
			(end 2.286 -0.254)
			(stroke
				(width 0)
				(type default)
			)
			(fill no)
			(layer "F.CrtYd")
		)
		(fp_line
			(start -2.286 -0.254)
			(end 2.286 -0.254)
			(stroke
				(width 0.1)
				(type default)
			)
			(layer "F.Fab")
		)
		(fp_line
			(start -2.286 7.366)
			(end -2.286 -0.254)
			(stroke
				(width 0.1)
				(type default)
			)
			(layer "F.Fab")
		)
		(fp_line
			(start 2.286 -0.254)
			(end 2.286 7.366)
			(stroke
				(width 0.1)
				(type default)
			)
			(layer "F.Fab")
		)
		(fp_line
			(start 2.286 7.366)
			(end -2.286 7.366)
			(stroke
				(width 0.1)
				(type default)
			)
			(layer "F.Fab")
		)
		(pad "1" smd rect
			(at 0 0)
			(size 2.54 3.048)
			(layers "F.Cu" "F.Mask" "F.Paste")
			(net "PVCCIOMCP_CPU1")
		)
		(pad "2" smd rect
			(at 0 7.112)
			(size 2.54 3.048)
			(layers "F.Cu" "F.Mask" "F.Paste")
			(net "GND")
		)
	)
	(footprint ""
		(layer "F.Cu")
		(at 392.557 -88.2015)
		(property "Reference" "R3P62"
			(at 0 0 0)
			(layer "F.SilkS")
			(hide yes)
			(effects
				(font
					(size 1.27 1.27)
				)
			)
		)
		(property "Value" ""
			(at 0 0 0)
			(layer "F.Fab")
			(effects
				(font
					(size 1.27 1.27)
				)
			)
		)
		(duplicate_pad_numbers_are_jumpers no)
		(fp_poly
			(pts
				(xy -0.2794 -0.1016) (xy 0.2794 -0.1016) (xy 0.2794 0.9906) (xy -0.2794 0.9906)
			)
			(stroke
				(width 0)
				(type default)
			)
			(fill no)
			(layer "F.CrtYd")
		)
		(fp_line
			(start -0.2794 -0.1016)
			(end -0.2794 0.9906)
			(stroke
				(width 0.1)
				(type default)
			)
			(layer "F.Fab")
		)
		(fp_line
			(start -0.2794 0.9906)
			(end 0.2794 0.9906)
			(stroke
				(width 0.1)
				(type default)
			)
			(layer "F.Fab")
		)
		(fp_line
			(start 0.2794 -0.1016)
			(end -0.2794 -0.1016)
			(stroke
				(width 0.1)
				(type default)
			)
			(layer "F.Fab")
		)
		(fp_line
			(start 0.2794 0.9906)
			(end 0.2794 -0.1016)
			(stroke
				(width 0.1)
				(type default)
			)
			(layer "F.Fab")
		)
		(pad "1" smd rect
			(at 0 0)
			(size 0.508 0.508)
			(layers "F.Cu" "F.Mask" "F.Paste")
			(net "P3V3_STBY")
		)
		(pad "2" smd rect
			(at 0 0.889)
			(size 0.508 0.508)
			(layers "F.Cu" "F.Mask" "F.Paste")
			(net "FM_FLASH_ATTACH_CFG_STRAP")
		)
		(zone
			(layer "F.Cu")
			(hatch none 0.5)
			(connect_pads
				(clearance 0)
			)
			(min_thickness 0.25)
			(keepout
				(tracks allowed)
				(vias not_allowed)
				(pads allowed)
				(copperpour not_allowed)
				(footprints allowed)
			)
			(placement
				(enabled no)
				(sheetname "")
			)
			(fill
				(thermal_gap 0.5)
				(thermal_bridge_width 0.5)
				(island_removal_mode 0)
			)
			(polygon
				(pts
					(xy 392.303 -87.9475) (xy 392.811 -87.9475) (xy 392.811 -87.5665) (xy 392.303 -87.5665)
				)
			)
		)
		(zone
			(layer "F.Cu")
			(hatch none 0.5)
			(connect_pads
				(clearance 0)
			)
			(min_thickness 0.25)
			(keepout
				(tracks not_allowed)
				(vias allowed)
				(pads allowed)
				(copperpour not_allowed)
				(footprints allowed)
			)
			(placement
				(enabled no)
				(sheetname "")
			)
			(fill
				(thermal_gap 0.5)
				(thermal_bridge_width 0.5)
				(island_removal_mode 0)
			)
			(polygon
				(pts
					(xy 392.303 -87.5665) (xy 392.811 -87.5665) (xy 392.811 -87.9475) (xy 392.303 -87.9475)
				)
			)
		)
	)
)
